(kicad_pcb
	(version 20260206)
	(generator "pcbnew")
	(generator_version "10.0")
	(general
		(thickness 1.6)
		(legacy_teardrops no)
	)
	(paper "A4")
	(title_block
		(title "Wiwynn_Tioga_Pass_MB.brd")
		(comment 1 "Tioga Pass / footprints 3915-3921 of 4770")
	)
	(layers
		(0 "F.Cu" signal "TOP")
		(4 "In1.Cu" signal "L2GND")
		(6 "In2.Cu" signal "L3")
		(8 "In3.Cu" signal "L4GND")
		(10 "In4.Cu" signal "L5")
		(12 "In5.Cu" signal "L6GND")
		(14 "In6.Cu" signal "L7VCC")
		(16 "In7.Cu" signal "L8VCC")
		(18 "In8.Cu" signal "L9GND")
		(20 "In9.Cu" signal "L10")
		(22 "In10.Cu" signal "L11GND")
		(24 "In11.Cu" signal "L12")
		(26 "In12.Cu" signal "L13GND")
		(2 "B.Cu" signal "BOTTOM")
		(9 "F.Adhes" user "F.Adhesive")
		(11 "B.Adhes" user "B.Adhesive")
		(13 "F.Paste" user "Package Geometry/Pastemask Top")
		(15 "B.Paste" user "Package Geometry/Pastemask Bottom")
		(5 "F.SilkS" user "Ref Des/Silkscreen Top")
		(7 "B.SilkS" user "Ref Des/Silkscreen Bottom")
		(1 "F.Mask" user "Board Geometry/Soldermask Top")
		(3 "B.Mask" user "Board Geometry/Soldermask Bottom")
		(17 "Dwgs.User" user "User.Drawings")
		(19 "Cmts.User" user "User.Comments")
		(21 "Eco1.User" user "User.Eco1")
		(23 "Eco2.User" user "User.Eco2")
		(25 "Edge.Cuts" user "Board Geometry/Outline")
		(27 "Margin" user)
		(31 "F.CrtYd" user "Package Geometry/Place Bound Top")
		(29 "B.CrtYd" user "Package Geometry/Place Bound Bottom")
		(35 "F.Fab" user "Ref Des/Assembly Top")
		(33 "B.Fab" user "Ref Des/Assembly Bottom")
	)
	(footprint ""
		(layer "B.Cu")
		(at 361.782614 -124.440442 -90)
		(property "Reference" "R780"
			(at 0.8382 -0.67818 270)
			(unlocked yes)
			(layer "B.SilkS")
			(effects
				(font
					(size 0.4064 0.254)
					(thickness 0.1524)
				)
				(justify left mirror)
			)
		)
		(property "Value" ""
			(at 0 0 90)
			(layer "B.Fab")
			(effects
				(font
					(size 1.27 1.27)
				)
				(justify mirror)
			)
		)
		(duplicate_pad_numbers_are_jumpers no)
		(fp_poly
			(pts
				(xy 0.2794 -0.1016) (xy -0.2794 -0.1016) (xy -0.2794 0.9906) (xy 0.2794 0.9906)
			)
			(stroke
				(width 0)
				(type default)
			)
			(fill no)
			(layer "B.CrtYd")
		)
		(fp_line
			(start -0.2794 0.9906)
			(end -0.2794 -0.1016)
			(stroke
				(width 0.1)
				(type default)
			)
			(layer "B.Fab")
		)
		(fp_line
			(start 0.2794 0.9906)
			(end -0.2794 0.9906)
			(stroke
				(width 0.1)
				(type default)
			)
			(layer "B.Fab")
		)
		(fp_line
			(start -0.2794 -0.1016)
			(end 0.2794 -0.1016)
			(stroke
				(width 0.1)
				(type default)
			)
			(layer "B.Fab")
		)
		(fp_line
			(start 0.2794 -0.1016)
			(end 0.2794 0.9906)
			(stroke
				(width 0.1)
				(type default)
			)
			(layer "B.Fab")
		)
		(pad "1" smd rect
			(at 0 0 90)
			(size 0.508 0.508)
			(layers "B.Cu" "B.Mask" "B.Paste")
			(net "P3E_CPU0_PE1_PCH_RXN<10>")
		)
		(pad "2" smd rect
			(at 0 0.889 90)
			(size 0.508 0.508)
			(layers "B.Cu" "B.Mask" "B.Paste")
			(net "P3E_CPU0_PE1_PCH_CON_RXN<10>")
		)
		(zone
			(layer "B.Cu")
			(hatch none 0.5)
			(connect_pads
				(clearance 0)
			)
			(min_thickness 0.25)
			(keepout
				(tracks not_allowed)
				(vias allowed)
				(pads allowed)
				(copperpour not_allowed)
				(footprints allowed)
			)
			(placement
				(enabled no)
				(sheetname "")
			)
			(fill
				(thermal_gap 0.5)
				(thermal_bridge_width 0.5)
				(island_removal_mode 0)
			)
			(polygon
				(pts
					(xy 361.147614 -124.186442) (xy 361.147614 -124.694442) (xy 361.528614 -124.694442) (xy 361.528614 -124.186442)
				)
			)
		)
		(zone
			(layer "B.Cu")
			(hatch none 0.5)
			(connect_pads
				(clearance 0)
			)
			(min_thickness 0.25)
			(keepout
				(tracks allowed)
				(vias not_allowed)
				(pads allowed)
				(copperpour not_allowed)
				(footprints allowed)
			)
			(placement
				(enabled no)
				(sheetname "")
			)
			(fill
				(thermal_gap 0.5)
				(thermal_bridge_width 0.5)
				(island_removal_mode 0)
			)
			(polygon
				(pts
					(xy 361.528614 -124.186442) (xy 361.528614 -124.694442) (xy 361.147614 -124.694442) (xy 361.147614 -124.186442)
				)
			)
		)
	)
	(footprint ""
		(layer "B.Cu")
		(at 350.9772 -86.741 90)
		(property "Reference" "R3P16"
			(at 0 0 90)
			(layer "B.SilkS")
			(hide yes)
			(effects
				(font
					(size 1.27 1.27)
				)
				(justify mirror)
			)
		)
		(property "Value" ""
			(at 0 0 90)
			(layer "B.Fab")
			(effects
				(font
					(size 1.27 1.27)
				)
				(justify mirror)
			)
		)
		(duplicate_pad_numbers_are_jumpers no)
		(fp_poly
			(pts
				(xy 0.2794 -0.1016) (xy -0.2794 -0.1016) (xy -0.2794 0.9906) (xy 0.2794 0.9906)
			)
			(stroke
				(width 0)
				(type default)
			)
			(fill no)
			(layer "B.CrtYd")
		)
		(fp_line
			(start 0.2794 -0.1016)
			(end 0.2794 0.9906)
			(stroke
				(width 0.1)
				(type default)
			)
			(layer "B.Fab")
		)
		(fp_line
			(start -0.2794 -0.1016)
			(end 0.2794 -0.1016)
			(stroke
				(width 0.1)
				(type default)
			)
			(layer "B.Fab")
		)
		(fp_line
			(start 0.2794 0.9906)
			(end -0.2794 0.9906)
			(stroke
				(width 0.1)
				(type default)
			)
			(layer "B.Fab")
		)
		(fp_line
			(start -0.2794 0.9906)
			(end -0.2794 -0.1016)
			(stroke
				(width 0.1)
				(type default)
			)
			(layer "B.Fab")
		)
		(pad "1" smd rect
			(at 0 0 270)
			(size 0.508 0.508)
			(layers "B.Cu" "B.Mask" "B.Paste")
			(net "VR_PVCCIO_CPU0_VINSEN")
		)
		(pad "2" smd rect
			(at 0 0.889 270)
			(size 0.508 0.508)
			(layers "B.Cu" "B.Mask" "B.Paste")
			(net "GND")
		)
		(zone
			(layer "B.Cu")
			(hatch none 0.5)
			(connect_pads
				(clearance 0)
			)
			(min_thickness 0.25)
			(keepout
				(tracks allowed)
				(vias not_allowed)
				(pads allowed)
				(copperpour not_allowed)
				(footprints allowed)
			)
			(placement
				(enabled no)
				(sheetname "")
			)
			(fill
				(thermal_gap 0.5)
				(thermal_bridge_width 0.5)
				(island_removal_mode 0)
			)
			(polygon
				(pts
					(xy 351.2312 -86.995) (xy 351.2312 -86.487) (xy 351.6122 -86.487) (xy 351.6122 -86.995)
				)
			)
		)
		(zone
			(layer "B.Cu")
			(hatch none 0.5)
			(connect_pads
				(clearance 0)
			)
			(min_thickness 0.25)
			(keepout
				(tracks not_allowed)
				(vias allowed)
				(pads allowed)
				(copperpour not_allowed)
				(footprints allowed)
			)
			(placement
				(enabled no)
				(sheetname "")
			)
			(fill
				(thermal_gap 0.5)
				(thermal_bridge_width 0.5)
				(island_removal_mode 0)
			)
			(polygon
				(pts
					(xy 351.6122 -86.995) (xy 351.6122 -86.487) (xy 351.2312 -86.487) (xy 351.2312 -86.995)
				)
			)
		)
	)
	(footprint ""
		(layer "B.Cu")
		(at 265.698732 -135.4074 90)
		(property "Reference" "C5M3"
			(at 0 0 90)
			(layer "B.SilkS")
			(hide yes)
			(effects
				(font
					(size 1.27 1.27)
				)
				(justify mirror)
			)
		)
		(property "Value" ""
			(at 0 0 90)
			(layer "B.Fab")
			(effects
				(font
					(size 1.27 1.27)
				)
				(justify mirror)
			)
		)
		(duplicate_pad_numbers_are_jumpers no)
		(fp_rect
			(start 0.500126 1.598422)
			(end -0.500126 -0.201422)
			(stroke
				(width 0)
				(type default)
			)
			(fill no)
			(layer "B.CrtYd")
		)
		(fp_line
			(start 0.500126 -0.201422)
			(end -0.500126 -0.201422)
			(stroke
				(width 0.1)
				(type default)
			)
			(layer "B.Fab")
		)
		(fp_line
			(start -0.500126 -0.201422)
			(end -0.500126 1.598422)
			(stroke
				(width 0.1)
				(type default)
			)
			(layer "B.Fab")
		)
		(fp_line
			(start 0.500126 1.598422)
			(end 0.500126 -0.201422)
			(stroke
				(width 0.1)
				(type default)
			)
			(layer "B.Fab")
		)
		(fp_line
			(start -0.500126 1.598422)
			(end 0.500126 1.598422)
			(stroke
				(width 0.1)
				(type default)
			)
			(layer "B.Fab")
		)
		(pad "1" smd rect
			(at 0 0)
			(size 0.889 0.9906)
			(layers "B.Cu" "B.Mask" "B.Paste")
			(net "PVDDQ_DEF")
		)
		(pad "2" smd rect
			(at 0 1.397)
			(size 0.889 0.9906)
			(layers "B.Cu" "B.Mask" "B.Paste")
			(net "GND")
		)
		(zone
			(layer "B.Cu")
			(hatch none 0.5)
			(connect_pads
				(clearance 0)
			)
			(min_thickness 0.25)
			(keepout
				(tracks not_allowed)
				(vias allowed)
				(pads allowed)
				(copperpour not_allowed)
				(footprints allowed)
			)
			(placement
				(enabled no)
				(sheetname "")
			)
			(fill
				(thermal_gap 0.5)
				(thermal_bridge_width 0.5)
				(island_removal_mode 0)
			)
			(polygon
				(pts
					(xy 266.651232 -135.9027) (xy 266.143232 -135.9027) (xy 266.143232 -134.9121) (xy 266.651232 -134.9121)
				)
			)
		)
		(zone
			(layer "B.Cu")
			(hatch none 0.5)
			(connect_pads
				(clearance 0)
			)
			(min_thickness 0.25)
			(keepout
				(tracks allowed)
				(vias not_allowed)
				(pads allowed)
				(copperpour not_allowed)
				(footprints allowed)
			)
			(placement
				(enabled no)
				(sheetname "")
			)
			(fill
				(thermal_gap 0.5)
				(thermal_bridge_width 0.5)
				(island_removal_mode 0)
			)
			(polygon
				(pts
					(xy 266.651232 -135.9027) (xy 266.143232 -135.9027) (xy 266.143232 -134.9121) (xy 266.651232 -134.9121)
				)
			)
		)
	)
	(footprint ""
		(layer "B.Cu")
		(at 318.543432 -145.034 -90)
		(property "Reference" "C4L4"
			(at 0 0 90)
			(layer "B.SilkS")
			(hide yes)
			(effects
				(font
					(size 1.27 1.27)
				)
				(justify mirror)
			)
		)
		(property "Value" ""
			(at 0 0 90)
			(layer "B.Fab")
			(effects
				(font
					(size 1.27 1.27)
				)
				(justify mirror)
			)
		)
		(duplicate_pad_numbers_are_jumpers no)
		(fp_poly
			(pts
				(xy 0.4953 -0.2032) (xy -0.4953 -0.2032) (xy -0.4953 1.6002) (xy 0.4953 1.6002)
			)
			(stroke
				(width 0)
				(type default)
			)
			(fill no)
			(layer "B.CrtYd")
		)
		(fp_line
			(start -0.4953 1.6002)
			(end 0.4953 1.6002)
			(stroke
				(width 0.1)
				(type default)
			)
			(layer "B.Fab")
		)
		(fp_line
			(start 0.4953 1.6002)
			(end 0.4953 -0.2032)
			(stroke
				(width 0.1)
				(type default)
			)
			(layer "B.Fab")
		)
		(fp_line
			(start -0.4953 -0.2032)
			(end -0.4953 1.6002)
			(stroke
				(width 0.1)
				(type default)
			)
			(layer "B.Fab")
		)
		(fp_line
			(start 0.4953 -0.2032)
			(end -0.4953 -0.2032)
			(stroke
				(width 0.1)
				(type default)
			)
			(layer "B.Fab")
		)
		(pad "1" smd rect
			(at 0 0 90)
			(size 0.762 0.889)
			(layers "B.Cu" "B.Mask" "B.Paste")
			(net "PVPP_DEF")
		)
		(pad "2" smd rect
			(at 0 1.397 90)
			(size 0.762 0.889)
			(layers "B.Cu" "B.Mask" "B.Paste")
			(net "GND")
		)
		(zone
			(layer "B.Cu")
			(hatch none 0.5)
			(connect_pads
				(clearance 0)
			)
			(min_thickness 0.25)
			(keepout
				(tracks not_allowed)
				(vias allowed)
				(pads allowed)
				(copperpour not_allowed)
				(footprints allowed)
			)
			(placement
				(enabled no)
				(sheetname "")
			)
			(fill
				(thermal_gap 0.5)
				(thermal_bridge_width 0.5)
				(island_removal_mode 0)
			)
			(polygon
				(pts
					(xy 318.098932 -144.653) (xy 318.098932 -145.415) (xy 317.590932 -145.415) (xy 317.590932 -144.653)
				)
			)
		)
	)
	(footprint ""
		(layer "B.Cu")
		(at 393.1412 -156.083 90)
		(property "Reference" "R2L8"
			(at 0 0 90)
			(layer "B.SilkS")
			(hide yes)
			(effects
				(font
					(size 1.27 1.27)
				)
				(justify mirror)
			)
		)
		(property "Value" ""
			(at 0 0 90)
			(layer "B.Fab")
			(effects
				(font
					(size 1.27 1.27)
				)
				(justify mirror)
			)
		)
		(duplicate_pad_numbers_are_jumpers no)
		(fp_poly
			(pts
				(xy 0.4953 -0.2032) (xy -0.4953 -0.2032) (xy -0.4953 1.6002) (xy 0.4953 1.6002)
			)
			(stroke
				(width 0)
				(type default)
			)
			(fill no)
			(layer "B.CrtYd")
		)
		(fp_line
			(start 0.4953 -0.2032)
			(end -0.4953 -0.2032)
			(stroke
				(width 0.1)
				(type default)
			)
			(layer "B.Fab")
		)
		(fp_line
			(start -0.4953 -0.2032)
			(end -0.4953 1.6002)
			(stroke
				(width 0.1)
				(type default)
			)
			(layer "B.Fab")
		)
		(fp_line
			(start 0.4953 1.6002)
			(end 0.4953 -0.2032)
			(stroke
				(width 0.1)
				(type default)
			)
			(layer "B.Fab")
		)
		(fp_line
			(start -0.4953 1.6002)
			(end 0.4953 1.6002)
			(stroke
				(width 0.1)
				(type default)
			)
			(layer "B.Fab")
		)
		(pad "1" smd rect
			(at 0 0 270)
			(size 0.762 0.889)
			(layers "B.Cu" "B.Mask" "B.Paste")
			(net "VSENSE_P1V05_PCH_STBY_AVSP")
		)
		(pad "2" smd rect
			(at 0 1.397 270)
			(size 0.762 0.889)
			(layers "B.Cu" "B.Mask" "B.Paste")
			(net "VR_P1V05_PCH_STBY_AVSP")
		)
		(zone
			(layer "B.Cu")
			(hatch none 0.5)
			(connect_pads
				(clearance 0)
			)
			(min_thickness 0.25)
			(keepout
				(tracks not_allowed)
				(vias allowed)
				(pads allowed)
				(copperpour not_allowed)
				(footprints allowed)
			)
			(placement
				(enabled no)
				(sheetname "")
			)
			(fill
				(thermal_gap 0.5)
				(thermal_bridge_width 0.5)
				(island_removal_mode 0)
			)
			(polygon
				(pts
					(xy 394.0937 -156.464) (xy 393.5857 -156.464) (xy 393.5857 -155.702) (xy 394.0937 -155.702)
				)
			)
		)
		(zone
			(layer "B.Cu")
			(hatch none 0.5)
			(connect_pads
				(clearance 0)
			)
			(min_thickness 0.25)
			(keepout
				(tracks allowed)
				(vias not_allowed)
				(pads allowed)
				(copperpour not_allowed)
				(footprints allowed)
			)
			(placement
				(enabled no)
				(sheetname "")
			)
			(fill
				(thermal_gap 0.5)
				(thermal_bridge_width 0.5)
				(island_removal_mode 0)
			)
			(polygon
				(pts
					(xy 394.0937 -155.702) (xy 393.5857 -155.702) (xy 393.5857 -156.464) (xy 394.0937 -156.464)
				)
			)
		)
	)
	(footprint ""
		(layer "B.Cu")
		(at 13.35024 -165.01618 -90)
		(property "Reference" "T1D12"
			(at 0 0 90)
			(layer "B.SilkS")
			(hide yes)
			(effects
				(font
					(size 1.27 1.27)
				)
				(justify mirror)
			)
		)
		(property "Value" "*"
			(at 3.4036 -4.46405 270)
			(unlocked yes)
			(layer "B.Fab")
			(hide yes)
			(effects
				(font
					(size 0.889 0.889)
					(thickness 0.1524)
				)
				(justify mirror)
			)
		)
		(property "Device Type" "TEST-PAD-12P-1-GP-U_DISCRET-GBA"
			(at 3.4036 -5.98805 270)
			(unlocked yes)
			(layer "B.Fab")
			(hide yes)
			(effects
				(font
					(size 0.889 0.889)
					(thickness 0.1524)
				)
				(justify mirror)
			)
		)
		(duplicate_pad_numbers_are_jumpers no)
		(fp_line
			(start -2.3622 3.4798)
			(end 2.3876 3.4798)
			(stroke
				(width 0.1524)
				(type default)
			)
			(layer "B.SilkS")
		)
		(fp_line
			(start 2.3876 3.4798)
			(end 2.3876 -4.826)
			(stroke
				(width 0.1524)
				(type default)
			)
			(layer "B.SilkS")
		)
		(fp_line
			(start -2.3622 -4.826)
			(end -2.3622 3.4798)
			(stroke
				(width 0.1524)
				(type default)
			)
			(layer "B.SilkS")
		)
		(fp_line
			(start 2.3876 -4.826)
			(end -2.3622 -4.826)
			(stroke
				(width 0.1524)
				(type default)
			)
			(layer "B.SilkS")
		)
		(fp_rect
			(start 2.6416 3.7338)
			(end -2.6162 -5.08)
			(stroke
				(width 0)
				(type default)
			)
			(fill no)
			(layer "B.CrtYd")
		)
		(fp_rect
			(start 2.6416 3.7338)
			(end -2.6162 -5.08)
			(stroke
				(width 0)
				(type default)
			)
			(fill no)
			(layer "B.Fab")
		)
		(pad "1" smd circle
			(at -0.496824 -1.301496 90)
			(size 0.6604 0.6604)
			(layers "B.Cu" "B.Mask" "B.Paste")
			(net "L14_85OHM_5INCH_DN")
		)
		(pad "2" smd circle
			(at 0.503936 -1.301496 90)
			(size 0.6604 0.6604)
			(layers "B.Cu" "B.Mask" "B.Paste")
			(net "L14_85OHM_5INCH_DP")
		)
		(pad "3" smd custom
			(at 0.00889 0.370078 90)
			(size 0.74295 0.74295)
			(layers "B.Cu" "B.Mask" "B.Paste")
			(net "GND")
			(options
				(clearance outline)
				(anchor circle)
			)
			(primitives
				(gr_poly
					(pts
						(xy -2.1209 -1.4859) (xy 2.1209 -1.4859) (xy 2.1209 1.4859) (xy 1.08585 1.4859) (xy 1.08585 0.4699)
						(xy -1.08585 0.4699) (xy -1.08585 1.4859) (xy -2.1209 1.4859)
					)
					(width 0)
					(fill yes)
				)
			)
		)
		(pad "4" thru_hole circle
			(at -1.266444 -3.851656 90)
			(size 1.4478 1.4478)
			(drill 1.0414)
			(layers "*.Cu" "*.Mask")
			(remove_unused_layers no)
			(net "GND")
			(clearance 0.1524)
			(thermal_gap 0.1524)
		)
		(pad "5" thru_hole circle
			(at 1.273556 -3.851656 90)
			(size 1.4478 1.4478)
			(drill 1.0414)
			(layers "*.Cu" "*.Mask")
			(remove_unused_layers no)
			(net "GND")
			(clearance 0.1524)
			(thermal_gap 0.1524)
		)
		(pad "6" thru_hole circle
			(at -1.266444 2.498344 90)
			(size 1.4478 1.4478)
			(drill 1.0414)
			(layers "*.Cu" "*.Mask")
			(remove_unused_layers no)
			(net "GND")
			(clearance 0.1524)
			(thermal_gap 0.1524)
		)
		(pad "7" thru_hole circle
			(at 1.273556 2.498344 90)
			(size 1.4478 1.4478)
			(drill 1.0414)
			(layers "*.Cu" "*.Mask")
			(remove_unused_layers no)
			(net "GND")
			(clearance 0.1524)
			(thermal_gap 0.1524)
		)
		(pad "8" thru_hole circle
			(at -1.27 -0.4572 90)
			(size 0.7112 0.7112)
			(drill 0.4064)
			(layers "*.Cu" "*.Mask")
			(remove_unused_layers no)
			(net "GND")
			(clearance 0.1016)
			(thermal_gap 0.1016)
		)
		(pad "9" thru_hole circle
			(at -1.27 0.762 90)
			(size 0.7112 0.7112)
			(drill 0.4064)
			(layers "*.Cu" "*.Mask")
			(remove_unused_layers no)
			(net "GND")
			(clearance 0.1016)
			(thermal_gap 0.1016)
		)
		(pad "10" thru_hole circle
			(at 0.0254 0.762 90)
			(size 0.7112 0.7112)
			(drill 0.4064)
			(layers "*.Cu" "*.Mask")
			(remove_unused_layers no)
			(net "GND")
			(clearance 0.1016)
			(thermal_gap 0.1016)
		)
		(pad "11" thru_hole circle
			(at 1.27 0.762 90)
			(size 0.7112 0.7112)
			(drill 0.4064)
			(layers "*.Cu" "*.Mask")
			(remove_unused_layers no)
			(net "GND")
			(clearance 0.1016)
			(thermal_gap 0.1016)
		)
		(pad "12" thru_hole circle
			(at 1.27 -0.4572 90)
			(size 0.7112 0.7112)
			(drill 0.4064)
			(layers "*.Cu" "*.Mask")
			(remove_unused_layers no)
			(net "GND")
			(clearance 0.1016)
			(thermal_gap 0.1016)
		)
	)
	(footprint ""
		(layer "B.Cu")
		(at 389.255 -66.167 90)
		(property "Reference" "R2T6"
			(at 0 0 90)
			(layer "B.SilkS")
			(hide yes)
			(effects
				(font
					(size 1.27 1.27)
				)
				(justify mirror)
			)
		)
		(property "Value" ""
			(at 0 0 90)
			(layer "B.Fab")
			(effects
				(font
					(size 1.27 1.27)
				)
				(justify mirror)
			)
		)
		(duplicate_pad_numbers_are_jumpers no)
		(fp_poly
			(pts
				(xy 0.2794 -0.1016) (xy -0.2794 -0.1016) (xy -0.2794 0.9906) (xy 0.2794 0.9906)
			)
			(stroke
				(width 0)
				(type default)
			)
			(fill no)
			(layer "B.CrtYd")
		)
		(fp_line
			(start 0.2794 -0.1016)
			(end 0.2794 0.9906)
			(stroke
				(width 0.1)
				(type default)
			)
			(layer "B.Fab")
		)
		(fp_line
			(start -0.2794 -0.1016)
			(end 0.2794 -0.1016)
			(stroke
				(width 0.1)
				(type default)
			)
			(layer "B.Fab")
		)
		(fp_line
			(start 0.2794 0.9906)
			(end -0.2794 0.9906)
			(stroke
				(width 0.1)
				(type default)
			)
			(layer "B.Fab")
		)
		(fp_line
			(start -0.2794 0.9906)
			(end -0.2794 -0.1016)
			(stroke
				(width 0.1)
				(type default)
			)
			(layer "B.Fab")
		)
		(pad "1" smd rect
			(at 0 0 270)
			(size 0.508 0.508)
			(layers "B.Cu" "B.Mask" "B.Paste")
			(net "P3V3_STBY")
		)
		(pad "2" smd rect
			(at 0 0.889 270)
			(size 0.508 0.508)
			(layers "B.Cu" "B.Mask" "B.Paste")
			(net "FM_BACKUP_BIOS_SEL_N")
		)
		(zone
			(layer "B.Cu")
			(hatch none 0.5)
			(connect_pads
				(clearance 0)
			)
			(min_thickness 0.25)
			(keepout
				(tracks allowed)
				(vias not_allowed)
				(pads allowed)
				(copperpour not_allowed)
				(footprints allowed)
			)
			(placement
				(enabled no)
				(sheetname "")
			)
			(fill
				(thermal_gap 0.5)
				(thermal_bridge_width 0.5)
				(island_removal_mode 0)
			)
			(polygon
				(pts
					(xy 389.509 -66.421) (xy 389.509 -65.913) (xy 389.89 -65.913) (xy 389.89 -66.421)
				)
			)
		)
		(zone
			(layer "B.Cu")
			(hatch none 0.5)
			(connect_pads
				(clearance 0)
			)
			(min_thickness 0.25)
			(keepout
				(tracks not_allowed)
				(vias allowed)
				(pads allowed)
				(copperpour not_allowed)
				(footprints allowed)
			)
			(placement
				(enabled no)
				(sheetname "")
			)
			(fill
				(thermal_gap 0.5)
				(thermal_bridge_width 0.5)
				(island_removal_mode 0)
			)
			(polygon
				(pts
					(xy 389.89 -66.421) (xy 389.89 -65.913) (xy 389.509 -65.913) (xy 389.509 -66.421)
				)
			)
		)
	)
)
